(kicad_pcb
	(version 20260206)
	(generator "pcbnew")
	(generator_version "10.0")
	(general
		(thickness 1.6)
		(legacy_teardrops no)
	)
	(paper "A4")
	(title_block
		(title "Wiwynn_Tioga_Pass_MB.brd")
		(comment 1 "Tioga Pass / footprints 87-93 of 4770")
	)
	(layers
		(0 "F.Cu" signal "TOP")
		(4 "In1.Cu" signal "L2GND")
		(6 "In2.Cu" signal "L3")
		(8 "In3.Cu" signal "L4GND")
		(10 "In4.Cu" signal "L5")
		(12 "In5.Cu" signal "L6GND")
		(14 "In6.Cu" signal "L7VCC")
		(16 "In7.Cu" signal "L8VCC")
		(18 "In8.Cu" signal "L9GND")
		(20 "In9.Cu" signal "L10")
		(22 "In10.Cu" signal "L11GND")
		(24 "In11.Cu" signal "L12")
		(26 "In12.Cu" signal "L13GND")
		(2 "B.Cu" signal "BOTTOM")
		(9 "F.Adhes" user "F.Adhesive")
		(11 "B.Adhes" user "B.Adhesive")
		(13 "F.Paste" user "Package Geometry/Pastemask Top")
		(15 "B.Paste" user "Package Geometry/Pastemask Bottom")
		(5 "F.SilkS" user "Ref Des/Silkscreen Top")
		(7 "B.SilkS" user "Ref Des/Silkscreen Bottom")
		(1 "F.Mask" user "Board Geometry/Soldermask Top")
		(3 "B.Mask" user "Board Geometry/Soldermask Bottom")
		(17 "Dwgs.User" user "User.Drawings")
		(19 "Cmts.User" user "User.Comments")
		(21 "Eco1.User" user "User.Eco1")
		(23 "Eco2.User" user "User.Eco2")
		(25 "Edge.Cuts" user "Board Geometry/Outline")
		(27 "Margin" user)
		(31 "F.CrtYd" user "Package Geometry/Place Bound Top")
		(29 "B.CrtYd" user "Package Geometry/Place Bound Bottom")
		(35 "F.Fab" user "Ref Des/Assembly Top")
		(33 "B.Fab" user "Ref Des/Assembly Bottom")
	)
	(footprint ""
		(layer "F.Cu")
		(at 164.084 -69.088 90)
		(property "Reference" "R4D51"
			(at 0 0 90)
			(layer "F.SilkS")
			(hide yes)
			(effects
				(font
					(size 1.27 1.27)
				)
			)
		)
		(property "Value" ""
			(at 0 0 90)
			(layer "F.Fab")
			(effects
				(font
					(size 1.27 1.27)
				)
			)
		)
		(duplicate_pad_numbers_are_jumpers no)
		(fp_poly
			(pts
				(xy -0.2794 -0.1016) (xy 0.2794 -0.1016) (xy 0.2794 0.9906) (xy -0.2794 0.9906)
			)
			(stroke
				(width 0)
				(type default)
			)
			(fill no)
			(layer "F.CrtYd")
		)
		(fp_line
			(start 0.2794 -0.1016)
			(end -0.2794 -0.1016)
			(stroke
				(width 0.1)
				(type default)
			)
			(layer "F.Fab")
		)
		(fp_line
			(start -0.2794 -0.1016)
			(end -0.2794 0.9906)
			(stroke
				(width 0.1)
				(type default)
			)
			(layer "F.Fab")
		)
		(fp_line
			(start 0.2794 0.9906)
			(end 0.2794 -0.1016)
			(stroke
				(width 0.1)
				(type default)
			)
			(layer "F.Fab")
		)
		(fp_line
			(start -0.2794 0.9906)
			(end 0.2794 0.9906)
			(stroke
				(width 0.1)
				(type default)
			)
			(layer "F.Fab")
		)
		(pad "1" smd rect
			(at 0 0 90)
			(size 0.508 0.508)
			(layers "F.Cu" "F.Mask" "F.Paste")
			(net "SVID_CLK0_CPU1_R")
		)
		(pad "2" smd rect
			(at 0 0.889 90)
			(size 0.508 0.508)
			(layers "F.Cu" "F.Mask" "F.Paste")
			(net "SVID_CLK_PVCCIO_CPU1")
		)
		(zone
			(layer "F.Cu")
			(hatch none 0.5)
			(connect_pads
				(clearance 0)
			)
			(min_thickness 0.25)
			(keepout
				(tracks allowed)
				(vias not_allowed)
				(pads allowed)
				(copperpour not_allowed)
				(footprints allowed)
			)
			(placement
				(enabled no)
				(sheetname "")
			)
			(fill
				(thermal_gap 0.5)
				(thermal_bridge_width 0.5)
				(island_removal_mode 0)
			)
			(polygon
				(pts
					(xy 164.338 -68.834) (xy 164.338 -69.342) (xy 164.719 -69.342) (xy 164.719 -68.834)
				)
			)
		)
		(zone
			(layer "F.Cu")
			(hatch none 0.5)
			(connect_pads
				(clearance 0)
			)
			(min_thickness 0.25)
			(keepout
				(tracks not_allowed)
				(vias allowed)
				(pads allowed)
				(copperpour not_allowed)
				(footprints allowed)
			)
			(placement
				(enabled no)
				(sheetname "")
			)
			(fill
				(thermal_gap 0.5)
				(thermal_bridge_width 0.5)
				(island_removal_mode 0)
			)
			(polygon
				(pts
					(xy 164.719 -68.834) (xy 164.719 -69.342) (xy 164.338 -69.342) (xy 164.338 -68.834)
				)
			)
		)
	)
	(footprint ""
		(layer "F.Cu")
		(at 476.377 -36.6395 180)
		(property "Reference" "R8G1"
			(at 0 0 180)
			(layer "F.SilkS")
			(hide yes)
			(effects
				(font
					(size 1.27 1.27)
				)
			)
		)
		(property "Value" ""
			(at 0 0 180)
			(layer "F.Fab")
			(effects
				(font
					(size 1.27 1.27)
				)
			)
		)
		(duplicate_pad_numbers_are_jumpers no)
		(fp_poly
			(pts
				(xy -0.2794 -0.1016) (xy 0.2794 -0.1016) (xy 0.2794 0.9906) (xy -0.2794 0.9906)
			)
			(stroke
				(width 0)
				(type default)
			)
			(fill no)
			(layer "F.CrtYd")
		)
		(fp_line
			(start 0.2794 0.9906)
			(end 0.2794 -0.1016)
			(stroke
				(width 0.1)
				(type default)
			)
			(layer "F.Fab")
		)
		(fp_line
			(start 0.2794 -0.1016)
			(end -0.2794 -0.1016)
			(stroke
				(width 0.1)
				(type default)
			)
			(layer "F.Fab")
		)
		(fp_line
			(start -0.2794 0.9906)
			(end 0.2794 0.9906)
			(stroke
				(width 0.1)
				(type default)
			)
			(layer "F.Fab")
		)
		(fp_line
			(start -0.2794 -0.1016)
			(end -0.2794 0.9906)
			(stroke
				(width 0.1)
				(type default)
			)
			(layer "F.Fab")
		)
		(pad "1" smd rect
			(at 0 0 180)
			(size 0.508 0.508)
			(layers "F.Cu" "F.Mask" "F.Paste")
			(net "CLK_50M_CKMNG_BMC_2_R")
		)
		(pad "2" smd rect
			(at 0 0.889 180)
			(size 0.508 0.508)
			(layers "F.Cu" "F.Mask" "F.Paste")
			(net "CLK_50M_CKMNG_BMC_2")
		)
		(zone
			(layer "F.Cu")
			(hatch none 0.5)
			(connect_pads
				(clearance 0)
			)
			(min_thickness 0.25)
			(keepout
				(tracks not_allowed)
				(vias allowed)
				(pads allowed)
				(copperpour not_allowed)
				(footprints allowed)
			)
			(placement
				(enabled no)
				(sheetname "")
			)
			(fill
				(thermal_gap 0.5)
				(thermal_bridge_width 0.5)
				(island_removal_mode 0)
			)
			(polygon
				(pts
					(xy 476.631 -37.2745) (xy 476.123 -37.2745) (xy 476.123 -36.8935) (xy 476.631 -36.8935)
				)
			)
		)
		(zone
			(layer "F.Cu")
			(hatch none 0.5)
			(connect_pads
				(clearance 0)
			)
			(min_thickness 0.25)
			(keepout
				(tracks allowed)
				(vias not_allowed)
				(pads allowed)
				(copperpour not_allowed)
				(footprints allowed)
			)
			(placement
				(enabled no)
				(sheetname "")
			)
			(fill
				(thermal_gap 0.5)
				(thermal_bridge_width 0.5)
				(island_removal_mode 0)
			)
			(polygon
				(pts
					(xy 476.631 -36.8935) (xy 476.123 -36.8935) (xy 476.123 -37.2745) (xy 476.631 -37.2745)
				)
			)
		)
	)
	(footprint ""
		(layer "F.Cu")
		(at 14.209268 -3.54203 180)
		(property "Reference" "R1G8"
			(at 0 0 180)
			(layer "F.SilkS")
			(hide yes)
			(effects
				(font
					(size 1.27 1.27)
				)
			)
		)
		(property "Value" ""
			(at 0 0 180)
			(layer "F.Fab")
			(effects
				(font
					(size 1.27 1.27)
				)
			)
		)
		(duplicate_pad_numbers_are_jumpers no)
		(fp_poly
			(pts
				(xy -0.2794 -0.1016) (xy 0.2794 -0.1016) (xy 0.2794 0.9906) (xy -0.2794 0.9906)
			)
			(stroke
				(width 0)
				(type default)
			)
			(fill no)
			(layer "F.CrtYd")
		)
		(fp_line
			(start 0.2794 0.9906)
			(end 0.2794 -0.1016)
			(stroke
				(width 0.1)
				(type default)
			)
			(layer "F.Fab")
		)
		(fp_line
			(start 0.2794 -0.1016)
			(end -0.2794 -0.1016)
			(stroke
				(width 0.1)
				(type default)
			)
			(layer "F.Fab")
		)
		(fp_line
			(start -0.2794 0.9906)
			(end 0.2794 0.9906)
			(stroke
				(width 0.1)
				(type default)
			)
			(layer "F.Fab")
		)
		(fp_line
			(start -0.2794 -0.1016)
			(end -0.2794 0.9906)
			(stroke
				(width 0.1)
				(type default)
			)
			(layer "F.Fab")
		)
		(pad "1" smd rect
			(at 0 0 180)
			(size 0.508 0.508)
			(layers "F.Cu" "F.Mask" "F.Paste")
			(net "IRQ_PVDDQ_GHJ_VRHOT_LVT3_R_N")
		)
		(pad "2" smd rect
			(at 0 0.889 180)
			(size 0.508 0.508)
			(layers "F.Cu" "F.Mask" "F.Paste")
			(net "IRQ_PVDDQ_GHJ_VRHOT_LVT3_N")
		)
		(zone
			(layer "F.Cu")
			(hatch none 0.5)
			(connect_pads
				(clearance 0)
			)
			(min_thickness 0.25)
			(keepout
				(tracks not_allowed)
				(vias allowed)
				(pads allowed)
				(copperpour not_allowed)
				(footprints allowed)
			)
			(placement
				(enabled no)
				(sheetname "")
			)
			(fill
				(thermal_gap 0.5)
				(thermal_bridge_width 0.5)
				(island_removal_mode 0)
			)
			(polygon
				(pts
					(xy 14.463268 -4.17703) (xy 13.955268 -4.17703) (xy 13.955268 -3.79603) (xy 14.463268 -3.79603)
				)
			)
		)
		(zone
			(layer "F.Cu")
			(hatch none 0.5)
			(connect_pads
				(clearance 0)
			)
			(min_thickness 0.25)
			(keepout
				(tracks allowed)
				(vias not_allowed)
				(pads allowed)
				(copperpour not_allowed)
				(footprints allowed)
			)
			(placement
				(enabled no)
				(sheetname "")
			)
			(fill
				(thermal_gap 0.5)
				(thermal_bridge_width 0.5)
				(island_removal_mode 0)
			)
			(polygon
				(pts
					(xy 14.463268 -3.79603) (xy 13.955268 -3.79603) (xy 13.955268 -4.17703) (xy 14.463268 -4.17703)
				)
			)
		)
	)
	(footprint ""
		(layer "F.Cu")
		(at 195.086986 -94.687898)
		(property "Reference" "CT60"
			(at 1.8288 -2.28473 0)
			(unlocked yes)
			(layer "F.SilkS")
			(effects
				(font
					(size 0.7874 0.5842)
					(thickness 0.1524)
				)
				(justify left)
			)
		)
		(property "Value" ""
			(at 0 0 0)
			(layer "F.Fab")
			(effects
				(font
					(size 1.27 1.27)
				)
			)
		)
		(duplicate_pad_numbers_are_jumpers no)
		(fp_poly
			(pts
				(xy 0.3048 -0.1016) (xy 0.3048 0.9906) (xy -0.3048 0.9906) (xy -0.3048 -0.1016)
			)
			(stroke
				(width 0)
				(type default)
			)
			(fill no)
			(layer "F.CrtYd")
		)
		(fp_line
			(start -0.3048 -0.1016)
			(end -0.3048 0.9906)
			(stroke
				(width 0.1)
				(type default)
			)
			(layer "F.Fab")
		)
		(fp_line
			(start -0.3048 0.9906)
			(end 0.3048 0.9906)
			(stroke
				(width 0.1)
				(type default)
			)
			(layer "F.Fab")
		)
		(fp_line
			(start 0.3048 -0.1016)
			(end -0.3048 -0.1016)
			(stroke
				(width 0.1)
				(type default)
			)
			(layer "F.Fab")
		)
		(fp_line
			(start 0.3048 0.9906)
			(end 0.3048 -0.1016)
			(stroke
				(width 0.1)
				(type default)
			)
			(layer "F.Fab")
		)
		(pad "1" smd rect
			(at 0 0)
			(size 0.508 0.508)
			(layers "F.Cu" "F.Mask" "F.Paste")
			(net "VR_PVSA_CPU0_BIREF1")
		)
		(pad "2" smd rect
			(at 0 0.889)
			(size 0.508 0.508)
			(layers "F.Cu" "F.Mask" "F.Paste")
			(net "GND")
		)
		(zone
			(layer "F.Cu")
			(hatch none 0.5)
			(connect_pads
				(clearance 0)
			)
			(min_thickness 0.25)
			(keepout
				(tracks allowed)
				(vias not_allowed)
				(pads allowed)
				(copperpour not_allowed)
				(footprints allowed)
			)
			(placement
				(enabled no)
				(sheetname "")
			)
			(fill
				(thermal_gap 0.5)
				(thermal_bridge_width 0.5)
				(island_removal_mode 0)
			)
			(polygon
				(pts
					(xy 194.832986 -94.433898) (xy 195.340986 -94.433898) (xy 195.340986 -94.052898) (xy 194.832986 -94.052898)
				)
			)
		)
		(zone
			(layer "F.Cu")
			(hatch none 0.5)
			(connect_pads
				(clearance 0)
			)
			(min_thickness 0.25)
			(keepout
				(tracks not_allowed)
				(vias allowed)
				(pads allowed)
				(copperpour not_allowed)
				(footprints allowed)
			)
			(placement
				(enabled no)
				(sheetname "")
			)
			(fill
				(thermal_gap 0.5)
				(thermal_bridge_width 0.5)
				(island_removal_mode 0)
			)
			(polygon
				(pts
					(xy 194.832986 -94.052898) (xy 195.340986 -94.052898) (xy 195.340986 -94.433898) (xy 194.832986 -94.433898)
				)
			)
		)
	)
	(footprint ""
		(layer "F.Cu")
		(at 395.351 -85.0265 180)
		(property "Reference" "R2U3"
			(at 0 0 180)
			(layer "F.SilkS")
			(hide yes)
			(effects
				(font
					(size 1.27 1.27)
				)
			)
		)
		(property "Value" ""
			(at 0 0 180)
			(layer "F.Fab")
			(effects
				(font
					(size 1.27 1.27)
				)
			)
		)
		(duplicate_pad_numbers_are_jumpers no)
		(fp_poly
			(pts
				(xy -0.2794 -0.1016) (xy 0.2794 -0.1016) (xy 0.2794 0.9906) (xy -0.2794 0.9906)
			)
			(stroke
				(width 0)
				(type default)
			)
			(fill no)
			(layer "F.CrtYd")
		)
		(fp_line
			(start 0.2794 0.9906)
			(end 0.2794 -0.1016)
			(stroke
				(width 0.1)
				(type default)
			)
			(layer "F.Fab")
		)
		(fp_line
			(start 0.2794 -0.1016)
			(end -0.2794 -0.1016)
			(stroke
				(width 0.1)
				(type default)
			)
			(layer "F.Fab")
		)
		(fp_line
			(start -0.2794 0.9906)
			(end 0.2794 0.9906)
			(stroke
				(width 0.1)
				(type default)
			)
			(layer "F.Fab")
		)
		(fp_line
			(start -0.2794 -0.1016)
			(end -0.2794 0.9906)
			(stroke
				(width 0.1)
				(type default)
			)
			(layer "F.Fab")
		)
		(pad "1" smd rect
			(at 0 0 180)
			(size 0.508 0.508)
			(layers "F.Cu" "F.Mask" "F.Paste")
			(net "P3V3_STBY")
		)
		(pad "2" smd rect
			(at 0 0.889 180)
			(size 0.508 0.508)
			(layers "F.Cu" "F.Mask" "F.Paste")
			(net "SMB_LAN_STBY_LVC3_SCL")
		)
		(zone
			(layer "F.Cu")
			(hatch none 0.5)
			(connect_pads
				(clearance 0)
			)
			(min_thickness 0.25)
			(keepout
				(tracks not_allowed)
				(vias allowed)
				(pads allowed)
				(copperpour not_allowed)
				(footprints allowed)
			)
			(placement
				(enabled no)
				(sheetname "")
			)
			(fill
				(thermal_gap 0.5)
				(thermal_bridge_width 0.5)
				(island_removal_mode 0)
			)
			(polygon
				(pts
					(xy 395.605 -85.6615) (xy 395.097 -85.6615) (xy 395.097 -85.2805) (xy 395.605 -85.2805)
				)
			)
		)
		(zone
			(layer "F.Cu")
			(hatch none 0.5)
			(connect_pads
				(clearance 0)
			)
			(min_thickness 0.25)
			(keepout
				(tracks allowed)
				(vias not_allowed)
				(pads allowed)
				(copperpour not_allowed)
				(footprints allowed)
			)
			(placement
				(enabled no)
				(sheetname "")
			)
			(fill
				(thermal_gap 0.5)
				(thermal_bridge_width 0.5)
				(island_removal_mode 0)
			)
			(polygon
				(pts
					(xy 395.605 -85.2805) (xy 395.097 -85.2805) (xy 395.097 -85.6615) (xy 395.605 -85.6615)
				)
			)
		)
	)
	(footprint ""
		(layer "F.Cu")
		(at 105.995978 -84.890102)
		(property "Reference" "C2D3"
			(at 0 0 0)
			(layer "F.SilkS")
			(hide yes)
			(effects
				(font
					(size 1.27 1.27)
				)
			)
		)
		(property "Value" ""
			(at 0 0 0)
			(layer "F.Fab")
			(effects
				(font
					(size 1.27 1.27)
				)
			)
		)
		(duplicate_pad_numbers_are_jumpers no)
		(fp_poly
			(pts
				(xy -0.4953 -0.2032) (xy 0.4953 -0.2032) (xy 0.4953 1.6002) (xy -0.4953 1.6002)
			)
			(stroke
				(width 0)
				(type default)
			)
			(fill no)
			(layer "F.CrtYd")
		)
		(fp_line
			(start -0.4953 -0.2032)
			(end 0.4953 -0.2032)
			(stroke
				(width 0.1)
				(type default)
			)
			(layer "F.Fab")
		)
		(fp_line
			(start -0.4953 1.6002)
			(end -0.4953 -0.2032)
			(stroke
				(width 0.1)
				(type default)
			)
			(layer "F.Fab")
		)
		(fp_line
			(start 0.4953 -0.2032)
			(end 0.4953 1.6002)
			(stroke
				(width 0.1)
				(type default)
			)
			(layer "F.Fab")
		)
		(fp_line
			(start 0.4953 1.6002)
			(end -0.4953 1.6002)
			(stroke
				(width 0.1)
				(type default)
			)
			(layer "F.Fab")
		)
		(pad "1" smd rect
			(at 0 0)
			(size 0.762 0.889)
			(layers "F.Cu" "F.Mask" "F.Paste")
			(net "PVDDQ_KLM")
		)
		(pad "2" smd rect
			(at 0 1.397)
			(size 0.762 0.889)
			(layers "F.Cu" "F.Mask" "F.Paste")
			(net "GND")
		)
		(zone
			(layer "F.Cu")
			(hatch none 0.5)
			(connect_pads
				(clearance 0)
			)
			(min_thickness 0.25)
			(keepout
				(tracks not_allowed)
				(vias allowed)
				(pads allowed)
				(copperpour not_allowed)
				(footprints allowed)
			)
			(placement
				(enabled no)
				(sheetname "")
			)
			(fill
				(thermal_gap 0.5)
				(thermal_bridge_width 0.5)
				(island_removal_mode 0)
			)
			(polygon
				(pts
					(xy 105.614978 -84.445602) (xy 106.376978 -84.445602) (xy 106.376978 -83.937602) (xy 105.614978 -83.937602)
				)
			)
		)
	)
	(footprint ""
		(layer "F.Cu")
		(at 25.520142 -109.542834 -90)
		(property "Reference" "C1C1"
			(at 1.397 -2.69367 90)
			(unlocked yes)
			(layer "F.SilkS")
			(effects
				(font
					(size 0.7874 0.5842)
					(thickness 0.1524)
				)
				(justify left)
			)
		)
		(property "Value" ""
			(at 0 0 270)
			(layer "F.Fab")
			(effects
				(font
					(size 1.27 1.27)
				)
			)
		)
		(duplicate_pad_numbers_are_jumpers no)
		(fp_line
			(start -3.400044 6.067044)
			(end -0.9017 6.067044)
			(stroke
				(width 0.1524)
				(type default)
			)
			(layer "F.SilkS")
		)
		(fp_line
			(start 0.9017 6.067044)
			(end 3.400044 6.067044)
			(stroke
				(width 0.1524)
				(type default)
			)
			(layer "F.SilkS")
		)
		(fp_line
			(start 3.400044 6.067044)
			(end 3.400044 0.028956)
			(stroke
				(width 0.1524)
				(type default)
			)
			(layer "F.SilkS")
		)
		(fp_line
			(start -0.9017 1.587754)
			(end -0.7239 1.587754)
			(stroke
				(width 0.1524)
				(type default)
			)
			(layer "F.SilkS")
		)
		(fp_line
			(start 0.7239 1.587754)
			(end 0.9017 1.587754)
			(stroke
				(width 0.1524)
				(type default)
			)
			(layer "F.SilkS")
		)
		(fp_line
			(start 0.9017 1.587754)
			(end 0.9017 -1.714246)
			(stroke
				(width 0.1524)
				(type default)
			)
			(layer "F.SilkS")
		)
		(fp_line
			(start -3.400044 0.028956)
			(end -3.400044 6.067044)
			(stroke
				(width 0.1524)
				(type default)
			)
			(layer "F.SilkS")
		)
		(fp_line
			(start 3.400044 0.028956)
			(end 2.638044 -0.733044)
			(stroke
				(width 0.1524)
				(type default)
			)
			(layer "F.SilkS")
		)
		(fp_line
			(start -2.638044 -0.733044)
			(end -3.400044 0.028956)
			(stroke
				(width 0.1524)
				(type default)
			)
			(layer "F.SilkS")
		)
		(fp_line
			(start -0.9017 -0.733044)
			(end -2.638044 -0.733044)
			(stroke
				(width 0.1524)
				(type default)
			)
			(layer "F.SilkS")
		)
		(fp_line
			(start 2.638044 -0.733044)
			(end 0.9017 -0.733044)
			(stroke
				(width 0.1524)
				(type default)
			)
			(layer "F.SilkS")
		)
		(fp_line
			(start -0.9017 -1.714246)
			(end -0.9017 1.587754)
			(stroke
				(width 0.1524)
				(type default)
			)
			(layer "F.SilkS")
		)
		(fp_line
			(start -0.7239 -1.714246)
			(end -0.9017 -1.714246)
			(stroke
				(width 0.1524)
				(type default)
			)
			(layer "F.SilkS")
		)
		(fp_line
			(start 0.9017 -1.714246)
			(end 0.7239 -1.714246)
			(stroke
				(width 0.1524)
				(type default)
			)
			(layer "F.SilkS")
		)
		(fp_poly
			(pts
				(xy -3.400044 6.067044) (xy 3.400044 6.067044) (xy 3.400044 0.028956) (xy 2.638044 -0.733044) (xy -2.638044 -0.733044)
				(xy -3.400044 0.028956)
			)
			(stroke
				(width 0)
				(type default)
			)
			(fill no)
			(layer "F.CrtYd")
		)
		(fp_line
			(start -3.400044 6.067044)
			(end 3.400044 6.067044)
			(stroke
				(width 0.1)
				(type default)
			)
			(layer "F.Fab")
		)
		(fp_line
			(start 3.400044 6.067044)
			(end 3.400044 0.028956)
			(stroke
				(width 0.1)
				(type default)
			)
			(layer "F.Fab")
		)
		(fp_line
			(start -3.400044 0.028956)
			(end -3.400044 6.067044)
			(stroke
				(width 0.1)
				(type default)
			)
			(layer "F.Fab")
		)
		(fp_line
			(start 3.400044 0.028956)
			(end 2.638044 -0.733044)
			(stroke
				(width 0.1)
				(type default)
			)
			(layer "F.Fab")
		)
		(fp_line
			(start -2.638044 -0.733044)
			(end -3.400044 0.028956)
			(stroke
				(width 0.1)
				(type default)
			)
			(layer "F.Fab")
		)
		(fp_line
			(start 2.638044 -0.733044)
			(end -2.638044 -0.733044)
			(stroke
				(width 0.1)
				(type default)
			)
			(layer "F.Fab")
		)
		(fp_circle
			(center 0 2.667)
			(end 0 -0.733044)
			(stroke
				(width 0.1)
				(type default)
			)
			(fill no)
			(layer "F.Fab")
		)
		(pad "1" smd rect
			(at 0 0 270)
			(size 0.7874 3.429)
			(layers "F.Cu" "F.Mask" "F.Paste")
			(net "VR_FET_SW_P12V_STBY_PVCCIN_CPU1")
		)
		(pad "2" smd rect
			(at 0 5.334 270)
			(size 0.7874 3.429)
			(layers "F.Cu" "F.Mask" "F.Paste")
			(net "GND")
		)
	)
)
